(kicad_pcb
	(version 20260206)
	(generator "pcbnew")
	(generator_version "10.0")
	(general
		(thickness 1.6)
		(legacy_teardrops no)
	)
	(paper "A4")
	(title_block
		(title "04192023_DAF0TMB3IC0_F0TG_MB_C_brd_V02_OCP.brd")
		(comment 1 "Grand Teton / footprints 3813-3819 of 8354")
	)
	(layers
		(0 "F.Cu" signal "TOP")
		(4 "In1.Cu" signal "GND")
		(6 "In2.Cu" signal "IN1")
		(8 "In3.Cu" signal "GND1")
		(10 "In4.Cu" signal "IN2")
		(12 "In5.Cu" signal "GND2")
		(14 "In6.Cu" signal "IN3")
		(16 "In7.Cu" signal "GND3")
		(18 "In8.Cu" signal "VCC")
		(20 "In9.Cu" signal "VCC1")
		(22 "In10.Cu" signal "GND4")
		(24 "In11.Cu" signal "IN4")
		(26 "In12.Cu" signal "GND5")
		(28 "In13.Cu" signal "IN5")
		(30 "In14.Cu" signal "GND6")
		(32 "In15.Cu" signal "IN6")
		(34 "In16.Cu" signal "GND7")
		(2 "B.Cu" signal "BOTTOM")
		(9 "F.Adhes" user "F.Adhesive")
		(11 "B.Adhes" user "B.Adhesive")
		(13 "F.Paste" user "Package Geometry/Pastemask Top")
		(15 "B.Paste" user "Package Geometry/Pastemask Bottom")
		(5 "F.SilkS" user "Ref Des/Silkscreen Top")
		(7 "B.SilkS" user "Ref Des/Silkscreen Bottom")
		(1 "F.Mask" user "Board Geometry/Soldermask Top")
		(3 "B.Mask" user "Board Geometry/Soldermask Bottom")
		(17 "Dwgs.User" user "User.Drawings")
		(19 "Cmts.User" user "User.Comments")
		(21 "Eco1.User" user "User.Eco1")
		(23 "Eco2.User" user "User.Eco2")
		(25 "Edge.Cuts" user "Board Geometry/Outline")
		(27 "Margin" user)
		(31 "F.CrtYd" user "Package Geometry/Place Bound Top")
		(29 "B.CrtYd" user "Package Geometry/Place Bound Bottom")
		(35 "F.Fab" user "Ref Des/Assembly Top")
		(33 "B.Fab" user "Ref Des/Assembly Bottom")
	)
	(footprint ""
		(layer "F.Cu")
		(at 334.795876 -70.098412 90)
		(property "Reference" "D79"
			(at -3.934714 -0.691642 90)
			(unlocked yes)
			(layer "F.SilkS")
			(effects
				(font
					(size 0.7874 0.5842)
					(thickness 0.1524)
				)
				(justify left)
			)
		)
		(property "Value" ""
			(at 0 0 90)
			(layer "F.Fab")
			(effects
				(font
					(size 1.27 1.27)
				)
			)
		)
		(duplicate_pad_numbers_are_jumpers no)
		(fp_line
			(start 1.16078 -0.4826)
			(end 1.16078 0.4826)
			(stroke
				(width 0.1524)
				(type default)
			)
			(layer "F.SilkS")
		)
		(fp_line
			(start 1.03378 -0.4826)
			(end 1.03378 0.4826)
			(stroke
				(width 0.1524)
				(type default)
			)
			(layer "F.SilkS")
		)
		(fp_line
			(start 0.90678 -0.4826)
			(end 0.90678 0.4826)
			(stroke
				(width 0.1524)
				(type default)
			)
			(layer "F.SilkS")
		)
		(fp_line
			(start -0.64008 -0.4826)
			(end 1.16078 -0.4826)
			(stroke
				(width 0.1524)
				(type default)
			)
			(layer "F.SilkS")
		)
		(fp_line
			(start -0.79248 -0.4826)
			(end 1.03378 -0.4826)
			(stroke
				(width 0.1524)
				(type default)
			)
			(layer "F.SilkS")
		)
		(fp_line
			(start -0.89408 -0.4826)
			(end 0.90678 -0.4826)
			(stroke
				(width 0.1524)
				(type default)
			)
			(layer "F.SilkS")
		)
		(fp_line
			(start 1.16078 0.4826)
			(end -0.64008 0.4826)
			(stroke
				(width 0.1524)
				(type default)
			)
			(layer "F.SilkS")
		)
		(fp_line
			(start 1.03378 0.4826)
			(end -0.79248 0.4826)
			(stroke
				(width 0.1524)
				(type default)
			)
			(layer "F.SilkS")
		)
		(fp_line
			(start 0.90678 0.4826)
			(end -0.90678 0.4826)
			(stroke
				(width 0.1524)
				(type default)
			)
			(layer "F.SilkS")
		)
		(fp_line
			(start -0.90678 0.4826)
			(end -0.90678 -0.4699)
			(stroke
				(width 0.1524)
				(type default)
			)
			(layer "F.SilkS")
		)
		(fp_line
			(start 0.499872 -0.249936)
			(end 0.499872 0.249936)
			(stroke
				(width 0.1)
				(type default)
			)
			(layer "F.Fab")
		)
		(fp_line
			(start -0.499872 -0.249936)
			(end 0.499872 -0.249936)
			(stroke
				(width 0.1)
				(type default)
			)
			(layer "F.Fab")
		)
		(fp_line
			(start 0.499872 0.249936)
			(end -0.499872 0.249936)
			(stroke
				(width 0.1)
				(type default)
			)
			(layer "F.Fab")
		)
		(fp_line
			(start -0.499872 0.249936)
			(end -0.499872 -0.249936)
			(stroke
				(width 0.1)
				(type default)
			)
			(layer "F.Fab")
		)
		(pad "A" smd rect
			(at -0.47498 0 90)
			(size 0.6096 0.7112)
			(layers "F.Cu" "F.Mask" "F.Paste")
			(net "LED_PWRGD_PVDD18_S5_P0_R")
		)
		(pad "C" smd rect
			(at 0.47498 0 90)
			(size 0.6096 0.7112)
			(layers "F.Cu" "F.Mask" "F.Paste")
			(net "LED_PWRGD_PVDD18_S5_P0_D")
		)
	)
	(footprint ""
		(layer "F.Cu")
		(at 68.432426 -155.237688)
		(property "Reference" "PC20"
			(at 0 0 0)
			(layer "F.SilkS")
			(hide yes)
			(effects
				(font
					(size 1.27 1.27)
				)
			)
		)
		(property "Value" ""
			(at 0 0 0)
			(layer "F.Fab")
			(effects
				(font
					(size 1.27 1.27)
				)
			)
		)
		(duplicate_pad_numbers_are_jumpers no)
		(fp_line
			(start -0.7874 -0.4064)
			(end 0.7874 -0.4064)
			(stroke
				(width 0.1524)
				(type default)
			)
			(layer "F.SilkS")
		)
		(fp_line
			(start -0.7874 0.4064)
			(end -0.7874 -0.4064)
			(stroke
				(width 0.1524)
				(type default)
			)
			(layer "F.SilkS")
		)
		(fp_line
			(start 0.7874 -0.4064)
			(end 0.7874 0.4064)
			(stroke
				(width 0.1524)
				(type default)
			)
			(layer "F.SilkS")
		)
		(fp_line
			(start 0.7874 0.4064)
			(end -0.7874 0.4064)
			(stroke
				(width 0.1524)
				(type default)
			)
			(layer "F.SilkS")
		)
		(fp_line
			(start -0.67945 -0.305054)
			(end -0.12065 -0.305054)
			(stroke
				(width 0.1)
				(type default)
			)
			(layer "F.Fab")
		)
		(fp_line
			(start -0.67945 0.3048)
			(end -0.67945 -0.305054)
			(stroke
				(width 0.1)
				(type default)
			)
			(layer "F.Fab")
		)
		(fp_line
			(start -0.12065 -0.305054)
			(end -0.12065 -0.2794)
			(stroke
				(width 0.1)
				(type default)
			)
			(layer "F.Fab")
		)
		(fp_line
			(start -0.12065 -0.2794)
			(end 0.12065 -0.2794)
			(stroke
				(width 0.1)
				(type default)
			)
			(layer "F.Fab")
		)
		(fp_line
			(start -0.12065 0.2794)
			(end -0.12065 0.3048)
			(stroke
				(width 0.1)
				(type default)
			)
			(layer "F.Fab")
		)
		(fp_line
			(start -0.12065 0.3048)
			(end -0.67945 0.3048)
			(stroke
				(width 0.1)
				(type default)
			)
			(layer "F.Fab")
		)
		(fp_line
			(start 0.120396 0.2794)
			(end -0.12065 0.2794)
			(stroke
				(width 0.1)
				(type default)
			)
			(layer "F.Fab")
		)
		(fp_line
			(start 0.120396 0.3048)
			(end 0.120396 0.2794)
			(stroke
				(width 0.1)
				(type default)
			)
			(layer "F.Fab")
		)
		(fp_line
			(start 0.12065 -0.3048)
			(end 0.67945 -0.3048)
			(stroke
				(width 0.1)
				(type default)
			)
			(layer "F.Fab")
		)
		(fp_line
			(start 0.12065 -0.2794)
			(end 0.12065 -0.3048)
			(stroke
				(width 0.1)
				(type default)
			)
			(layer "F.Fab")
		)
		(fp_line
			(start 0.67945 -0.3048)
			(end 0.67945 0.3048)
			(stroke
				(width 0.1)
				(type default)
			)
			(layer "F.Fab")
		)
		(fp_line
			(start 0.67945 0.3048)
			(end 0.120396 0.3048)
			(stroke
				(width 0.1)
				(type default)
			)
			(layer "F.Fab")
		)
		(pad "1" smd circle
			(at -0.40005 0)
			(size 0 0)
			(layers "F.Cu" "F.Mask" "F.Paste")
			(net "PVDD18_S5_P1_VCC")
		)
		(pad "2" smd circle
			(at 0.40005 0)
			(size 0 0)
			(layers "F.Cu" "F.Mask" "F.Paste")
			(net "GND")
		)
	)
	(footprint ""
		(layer "F.Cu")
		(at 112.649 -411.1498)
		(property "Reference" "C68"
			(at 0 0 0)
			(layer "F.SilkS")
			(hide yes)
			(effects
				(font
					(size 1.27 1.27)
				)
			)
		)
		(property "Value" ""
			(at 0 0 0)
			(layer "F.Fab")
			(effects
				(font
					(size 1.27 1.27)
				)
			)
		)
		(duplicate_pad_numbers_are_jumpers no)
		(fp_line
			(start -0.7874 -0.4064)
			(end 0.7874 -0.4064)
			(stroke
				(width 0.1524)
				(type default)
			)
			(layer "F.SilkS")
		)
		(fp_line
			(start -0.7874 0.4064)
			(end -0.7874 -0.4064)
			(stroke
				(width 0.1524)
				(type default)
			)
			(layer "F.SilkS")
		)
		(fp_line
			(start 0.7874 -0.4064)
			(end 0.7874 0.4064)
			(stroke
				(width 0.1524)
				(type default)
			)
			(layer "F.SilkS")
		)
		(fp_line
			(start 0.7874 0.4064)
			(end -0.7874 0.4064)
			(stroke
				(width 0.1524)
				(type default)
			)
			(layer "F.SilkS")
		)
		(fp_line
			(start -0.67945 -0.305054)
			(end -0.12065 -0.305054)
			(stroke
				(width 0.1)
				(type default)
			)
			(layer "F.Fab")
		)
		(fp_line
			(start -0.67945 0.3048)
			(end -0.67945 -0.305054)
			(stroke
				(width 0.1)
				(type default)
			)
			(layer "F.Fab")
		)
		(fp_line
			(start -0.12065 -0.305054)
			(end -0.12065 -0.2794)
			(stroke
				(width 0.1)
				(type default)
			)
			(layer "F.Fab")
		)
		(fp_line
			(start -0.12065 -0.2794)
			(end 0.12065 -0.2794)
			(stroke
				(width 0.1)
				(type default)
			)
			(layer "F.Fab")
		)
		(fp_line
			(start -0.12065 0.2794)
			(end -0.12065 0.3048)
			(stroke
				(width 0.1)
				(type default)
			)
			(layer "F.Fab")
		)
		(fp_line
			(start -0.12065 0.3048)
			(end -0.67945 0.3048)
			(stroke
				(width 0.1)
				(type default)
			)
			(layer "F.Fab")
		)
		(fp_line
			(start 0.120396 0.2794)
			(end -0.12065 0.2794)
			(stroke
				(width 0.1)
				(type default)
			)
			(layer "F.Fab")
		)
		(fp_line
			(start 0.120396 0.3048)
			(end 0.120396 0.2794)
			(stroke
				(width 0.1)
				(type default)
			)
			(layer "F.Fab")
		)
		(fp_line
			(start 0.12065 -0.3048)
			(end 0.67945 -0.3048)
			(stroke
				(width 0.1)
				(type default)
			)
			(layer "F.Fab")
		)
		(fp_line
			(start 0.12065 -0.2794)
			(end 0.12065 -0.3048)
			(stroke
				(width 0.1)
				(type default)
			)
			(layer "F.Fab")
		)
		(fp_line
			(start 0.67945 -0.3048)
			(end 0.67945 0.3048)
			(stroke
				(width 0.1)
				(type default)
			)
			(layer "F.Fab")
		)
		(fp_line
			(start 0.67945 0.3048)
			(end 0.120396 0.3048)
			(stroke
				(width 0.1)
				(type default)
			)
			(layer "F.Fab")
		)
		(pad "1" smd circle
			(at -0.40005 0)
			(size 0 0)
			(layers "F.Cu" "F.Mask" "F.Paste")
			(net "P3V3_9ZXL045_P1_VDDA")
		)
		(pad "2" smd circle
			(at 0.40005 0)
			(size 0 0)
			(layers "F.Cu" "F.Mask" "F.Paste")
			(net "GND")
		)
	)
	(footprint ""
		(layer "F.Cu")
		(at 277.581106 -414.966404)
		(property "Reference" "R6783"
			(at 0 0 0)
			(layer "F.SilkS")
			(hide yes)
			(effects
				(font
					(size 1.27 1.27)
				)
			)
		)
		(property "Value" ""
			(at 0 0 0)
			(layer "F.Fab")
			(effects
				(font
					(size 1.27 1.27)
				)
			)
		)
		(duplicate_pad_numbers_are_jumpers no)
		(fp_line
			(start -0.7874 -0.4064)
			(end 0.7874 -0.4064)
			(stroke
				(width 0.1524)
				(type default)
			)
			(layer "F.SilkS")
		)
		(fp_line
			(start -0.7874 0.4064)
			(end -0.7874 -0.4064)
			(stroke
				(width 0.1524)
				(type default)
			)
			(layer "F.SilkS")
		)
		(fp_line
			(start 0.7874 -0.4064)
			(end 0.7874 0.4064)
			(stroke
				(width 0.1524)
				(type default)
			)
			(layer "F.SilkS")
		)
		(fp_line
			(start 0.7874 0.4064)
			(end -0.7874 0.4064)
			(stroke
				(width 0.1524)
				(type default)
			)
			(layer "F.SilkS")
		)
		(fp_line
			(start -0.67945 -0.305054)
			(end -0.12065 -0.305054)
			(stroke
				(width 0.1)
				(type default)
			)
			(layer "F.Fab")
		)
		(fp_line
			(start -0.67945 0.3048)
			(end -0.67945 -0.305054)
			(stroke
				(width 0.1)
				(type default)
			)
			(layer "F.Fab")
		)
		(fp_line
			(start -0.12065 -0.305054)
			(end -0.12065 -0.2794)
			(stroke
				(width 0.1)
				(type default)
			)
			(layer "F.Fab")
		)
		(fp_line
			(start -0.12065 -0.2794)
			(end 0.12065 -0.2794)
			(stroke
				(width 0.1)
				(type default)
			)
			(layer "F.Fab")
		)
		(fp_line
			(start -0.12065 0.2794)
			(end -0.12065 0.3048)
			(stroke
				(width 0.1)
				(type default)
			)
			(layer "F.Fab")
		)
		(fp_line
			(start -0.12065 0.3048)
			(end -0.67945 0.3048)
			(stroke
				(width 0.1)
				(type default)
			)
			(layer "F.Fab")
		)
		(fp_line
			(start 0.120396 0.2794)
			(end -0.12065 0.2794)
			(stroke
				(width 0.1)
				(type default)
			)
			(layer "F.Fab")
		)
		(fp_line
			(start 0.120396 0.3048)
			(end 0.120396 0.2794)
			(stroke
				(width 0.1)
				(type default)
			)
			(layer "F.Fab")
		)
		(fp_line
			(start 0.12065 -0.3048)
			(end 0.67945 -0.3048)
			(stroke
				(width 0.1)
				(type default)
			)
			(layer "F.Fab")
		)
		(fp_line
			(start 0.12065 -0.2794)
			(end 0.12065 -0.3048)
			(stroke
				(width 0.1)
				(type default)
			)
			(layer "F.Fab")
		)
		(fp_line
			(start 0.67945 -0.3048)
			(end 0.67945 0.3048)
			(stroke
				(width 0.1)
				(type default)
			)
			(layer "F.Fab")
		)
		(fp_line
			(start 0.67945 0.3048)
			(end 0.120396 0.3048)
			(stroke
				(width 0.1)
				(type default)
			)
			(layer "F.Fab")
		)
		(pad "1" smd circle
			(at -0.40005 0)
			(size 0 0)
			(layers "F.Cu" "F.Mask" "F.Paste")
			(net "SMB_MUX_RT_ROM_R1_SDA")
		)
		(pad "2" smd circle
			(at 0.40005 0)
			(size 0 0)
			(layers "F.Cu" "F.Mask" "F.Paste")
			(net "SMB_HOST_CLK_3V3AUX_SDA_R1")
		)
	)
	(footprint ""
		(layer "F.Cu")
		(at 419.96106 -353.78009 90)
		(property "Reference" "PC203"
			(at 0 0 90)
			(layer "F.SilkS")
			(hide yes)
			(effects
				(font
					(size 1.27 1.27)
				)
			)
		)
		(property "Value" ""
			(at 0 0 90)
			(layer "F.Fab")
			(effects
				(font
					(size 1.27 1.27)
				)
			)
		)
		(duplicate_pad_numbers_are_jumpers no)
		(fp_line
			(start 0.7874 -0.4064)
			(end 0.7874 0.4064)
			(stroke
				(width 0.1524)
				(type default)
			)
			(layer "F.SilkS")
		)
		(fp_line
			(start -0.7874 -0.4064)
			(end 0.7874 -0.4064)
			(stroke
				(width 0.1524)
				(type default)
			)
			(layer "F.SilkS")
		)
		(fp_line
			(start 0.7874 0.4064)
			(end 0.37211 0.4064)
			(stroke
				(width 0.1524)
				(type default)
			)
			(layer "F.SilkS")
		)
		(fp_line
			(start -0.18669 0.4064)
			(end -0.7874 0.4064)
			(stroke
				(width 0.1524)
				(type default)
			)
			(layer "F.SilkS")
		)
		(fp_line
			(start -0.7874 0.4064)
			(end -0.7874 -0.4064)
			(stroke
				(width 0.1524)
				(type default)
			)
			(layer "F.SilkS")
		)
		(fp_line
			(start -0.12065 -0.305054)
			(end -0.12065 -0.2794)
			(stroke
				(width 0.1)
				(type default)
			)
			(layer "F.Fab")
		)
		(fp_line
			(start -0.67945 -0.305054)
			(end -0.12065 -0.305054)
			(stroke
				(width 0.1)
				(type default)
			)
			(layer "F.Fab")
		)
		(fp_line
			(start 0.67945 -0.3048)
			(end 0.67945 0.3048)
			(stroke
				(width 0.1)
				(type default)
			)
			(layer "F.Fab")
		)
		(fp_line
			(start 0.12065 -0.3048)
			(end 0.67945 -0.3048)
			(stroke
				(width 0.1)
				(type default)
			)
			(layer "F.Fab")
		)
		(fp_line
			(start 0.12065 -0.2794)
			(end 0.12065 -0.3048)
			(stroke
				(width 0.1)
				(type default)
			)
			(layer "F.Fab")
		)
		(fp_line
			(start -0.12065 -0.2794)
			(end 0.12065 -0.2794)
			(stroke
				(width 0.1)
				(type default)
			)
			(layer "F.Fab")
		)
		(fp_line
			(start 0.120396 0.2794)
			(end -0.12065 0.2794)
			(stroke
				(width 0.1)
				(type default)
			)
			(layer "F.Fab")
		)
		(fp_line
			(start -0.12065 0.2794)
			(end -0.12065 0.3048)
			(stroke
				(width 0.1)
				(type default)
			)
			(layer "F.Fab")
		)
		(fp_line
			(start 0.67945 0.3048)
			(end 0.120396 0.3048)
			(stroke
				(width 0.1)
				(type default)
			)
			(layer "F.Fab")
		)
		(fp_line
			(start 0.120396 0.3048)
			(end 0.120396 0.2794)
			(stroke
				(width 0.1)
				(type default)
			)
			(layer "F.Fab")
		)
		(fp_line
			(start -0.12065 0.3048)
			(end -0.67945 0.3048)
			(stroke
				(width 0.1)
				(type default)
			)
			(layer "F.Fab")
		)
		(fp_line
			(start -0.67945 0.3048)
			(end -0.67945 -0.305054)
			(stroke
				(width 0.1)
				(type default)
			)
			(layer "F.Fab")
		)
		(pad "1" smd circle
			(at -0.40005 0 90)
			(size 0 0)
			(layers "F.Cu" "F.Mask" "F.Paste")
			(net "PVDD11_S3_P0_VCC1")
		)
		(pad "2" smd circle
			(at 0.40005 0 90)
			(size 0 0)
			(layers "F.Cu" "F.Mask" "F.Paste")
			(net "GND")
		)
	)
	(footprint ""
		(layer "F.Cu")
		(at 42.967402 -376.85726 180)
		(property "Reference" "C834"
			(at 0 0 180)
			(layer "F.SilkS")
			(hide yes)
			(effects
				(font
					(size 1.27 1.27)
				)
			)
		)
		(property "Value" ""
			(at 0 0 180)
			(layer "F.Fab")
			(effects
				(font
					(size 1.27 1.27)
				)
			)
		)
		(duplicate_pad_numbers_are_jumpers no)
		(fp_line
			(start 0.299974 0.150114)
			(end -0.299974 0.150114)
			(stroke
				(width 0.1)
				(type default)
			)
			(layer "F.Fab")
		)
		(fp_line
			(start 0.299974 -0.150114)
			(end 0.299974 0.150114)
			(stroke
				(width 0.1)
				(type default)
			)
			(layer "F.Fab")
		)
		(fp_line
			(start -0.299974 0.150114)
			(end -0.299974 -0.150114)
			(stroke
				(width 0.1)
				(type default)
			)
			(layer "F.Fab")
		)
		(fp_line
			(start -0.299974 -0.150114)
			(end 0.299974 -0.150114)
			(stroke
				(width 0.1)
				(type default)
			)
			(layer "F.Fab")
		)
		(pad "1" smd rect
			(at -0.2667 0 180)
			(size 0.3048 0.381)
			(layers "F.Cu" "F.Mask" "F.Paste")
			(net "P5E_CPU1_P0_TX_C_DN<1>")
		)
		(pad "2" smd rect
			(at 0.2667 0 180)
			(size 0.3048 0.381)
			(layers "F.Cu" "F.Mask" "F.Paste")
			(net "P5E_CPU1_P0_TX_DN<1>")
		)
	)
	(footprint ""
		(layer "F.Cu")
		(at 410.479748 -17.624298 90)
		(property "Reference" "C44"
			(at 0 0 90)
			(layer "F.SilkS")
			(hide yes)
			(effects
				(font
					(size 1.27 1.27)
				)
			)
		)
		(property "Value" ""
			(at 0 0 90)
			(layer "F.Fab")
			(effects
				(font
					(size 1.27 1.27)
				)
			)
		)
		(duplicate_pad_numbers_are_jumpers no)
		(fp_line
			(start 0.299974 -0.150114)
			(end 0.299974 0.150114)
			(stroke
				(width 0.1)
				(type default)
			)
			(layer "F.Fab")
		)
		(fp_line
			(start -0.299974 -0.150114)
			(end 0.299974 -0.150114)
			(stroke
				(width 0.1)
				(type default)
			)
			(layer "F.Fab")
		)
		(fp_line
			(start 0.299974 0.150114)
			(end -0.299974 0.150114)
			(stroke
				(width 0.1)
				(type default)
			)
			(layer "F.Fab")
		)
		(fp_line
			(start -0.299974 0.150114)
			(end -0.299974 -0.150114)
			(stroke
				(width 0.1)
				(type default)
			)
			(layer "F.Fab")
		)
		(pad "1" smd rect
			(at -0.2667 0 90)
			(size 0.3048 0.381)
			(layers "F.Cu" "F.Mask" "F.Paste")
			(net "P5E_CPU0_G3_TX_C_DP<8>")
		)
		(pad "2" smd rect
			(at 0.2667 0 90)
			(size 0.3048 0.381)
			(layers "F.Cu" "F.Mask" "F.Paste")
			(net "P5E_CPU0_G3_TX_DP<8>")
		)
	)
)
